(kicad_pcb
	(version 20260206)
	(generator "pcbnew")
	(generator_version "10.0")
	(general
		(thickness 1.6)
		(legacy_teardrops no)
	)
	(paper "A4")
	(title_block
		(title "01162023_DA0F0TEBIF0_F0T_Expander_BD_F_brd_V02_OCP.brd")
		(comment 1 "Grand Teton / footprints 2756-2761 of 9728")
	)
	(layers
		(0 "F.Cu" signal "TOP")
		(4 "In1.Cu" signal "GND")
		(6 "In2.Cu" signal "VCC")
		(8 "In3.Cu" signal "VCC1")
		(10 "In4.Cu" signal "GND1")
		(12 "In5.Cu" signal "IN1")
		(14 "In6.Cu" signal "GND2")
		(16 "In7.Cu" signal "IN2")
		(18 "In8.Cu" signal "GND3")
		(20 "In9.Cu" signal "IN3")
		(22 "In10.Cu" signal "GND4")
		(24 "In11.Cu" signal "IN4")
		(26 "In12.Cu" signal "GND5")
		(28 "In13.Cu" signal "IN5")
		(30 "In14.Cu" signal "GND6")
		(32 "In15.Cu" signal "IN6")
		(34 "In16.Cu" signal "GND7")
		(2 "B.Cu" signal "BOTTOM")
		(9 "F.Adhes" user "F.Adhesive")
		(11 "B.Adhes" user "B.Adhesive")
		(13 "F.Paste" user "Package Geometry/Pastemask Top")
		(15 "B.Paste" user "Package Geometry/Pastemask Bottom")
		(5 "F.SilkS" user "Ref Des/Silkscreen Top")
		(7 "B.SilkS" user "Ref Des/Silkscreen Bottom")
		(1 "F.Mask" user "Board Geometry/Soldermask Top")
		(3 "B.Mask" user "Board Geometry/Soldermask Bottom")
		(17 "Dwgs.User" user "User.Drawings")
		(19 "Cmts.User" user "User.Comments")
		(21 "Eco1.User" user "User.Eco1")
		(23 "Eco2.User" user "User.Eco2")
		(25 "Edge.Cuts" user "Board Geometry/Outline")
		(27 "Margin" user)
		(31 "F.CrtYd" user "Package Geometry/Place Bound Top")
		(29 "B.CrtYd" user "Package Geometry/Place Bound Bottom")
		(35 "F.Fab" user "Ref Des/Assembly Top")
		(33 "B.Fab" user "Ref Des/Assembly Bottom")
	)
	(footprint ""
		(layer "F.Cu")
		(at 235.623608 -150.959566 180)
		(property "Reference" "R1210"
			(at 0 0 180)
			(layer "F.SilkS")
			(hide yes)
			(effects
				(font
					(size 1.27 1.27)
				)
			)
		)
		(property "Value" ""
			(at 0 0 180)
			(layer "F.Fab")
			(effects
				(font
					(size 1.27 1.27)
				)
			)
		)
		(duplicate_pad_numbers_are_jumpers no)
		(fp_line
			(start -0.7874 -0.4064)
			(end 0.7874 -0.4064)
			(stroke
				(width 0.1524)
				(type default)
			)
			(layer "F.SilkS")
		)
		(fp_line
			(start 0.67945 0.3048)
			(end 0.120396 0.3048)
			(stroke
				(width 0.1)
				(type default)
			)
			(layer "F.Fab")
		)
		(fp_line
			(start 0.67945 -0.3048)
			(end 0.67945 0.3048)
			(stroke
				(width 0.1)
				(type default)
			)
			(layer "F.Fab")
		)
		(fp_line
			(start 0.12065 -0.2794)
			(end 0.12065 -0.3048)
			(stroke
				(width 0.1)
				(type default)
			)
			(layer "F.Fab")
		)
		(fp_line
			(start 0.12065 -0.3048)
			(end 0.67945 -0.3048)
			(stroke
				(width 0.1)
				(type default)
			)
			(layer "F.Fab")
		)
		(fp_line
			(start 0.120396 0.3048)
			(end 0.120396 0.2794)
			(stroke
				(width 0.1)
				(type default)
			)
			(layer "F.Fab")
		)
		(fp_line
			(start 0.120396 0.2794)
			(end -0.12065 0.2794)
			(stroke
				(width 0.1)
				(type default)
			)
			(layer "F.Fab")
		)
		(fp_line
			(start -0.12065 0.3048)
			(end -0.67945 0.3048)
			(stroke
				(width 0.1)
				(type default)
			)
			(layer "F.Fab")
		)
		(fp_line
			(start -0.12065 0.2794)
			(end -0.12065 0.3048)
			(stroke
				(width 0.1)
				(type default)
			)
			(layer "F.Fab")
		)
		(fp_line
			(start -0.12065 -0.2794)
			(end 0.12065 -0.2794)
			(stroke
				(width 0.1)
				(type default)
			)
			(layer "F.Fab")
		)
		(fp_line
			(start -0.12065 -0.305054)
			(end -0.12065 -0.2794)
			(stroke
				(width 0.1)
				(type default)
			)
			(layer "F.Fab")
		)
		(fp_line
			(start -0.67945 0.3048)
			(end -0.67945 -0.305054)
			(stroke
				(width 0.1)
				(type default)
			)
			(layer "F.Fab")
		)
		(fp_line
			(start -0.67945 -0.305054)
			(end -0.12065 -0.305054)
			(stroke
				(width 0.1)
				(type default)
			)
			(layer "F.Fab")
		)
		(pad "1" smd circle
			(at -0.40005 0 180)
			(size 0 0)
			(layers "F.Cu" "F.Mask" "F.Paste")
			(net "CLK_100M_PEX2_REF_R_DN")
		)
		(pad "2" smd circle
			(at 0.40005 0 180)
			(size 0 0)
			(layers "F.Cu" "F.Mask" "F.Paste")
			(net "CLK_100M_PEX2_REF_DN")
		)
	)
	(footprint ""
		(layer "F.Cu")
		(at 394.389356 -242.9764)
		(property "Reference" "R6613"
			(at 0 0 0)
			(layer "F.SilkS")
			(hide yes)
			(effects
				(font
					(size 1.27 1.27)
				)
			)
		)
		(property "Value" ""
			(at 0 0 0)
			(layer "F.Fab")
			(effects
				(font
					(size 1.27 1.27)
				)
			)
		)
		(duplicate_pad_numbers_are_jumpers no)
		(fp_line
			(start -0.7874 -0.4064)
			(end 0.7874 -0.4064)
			(stroke
				(width 0.1524)
				(type default)
			)
			(layer "F.SilkS")
		)
		(fp_line
			(start -0.7874 0.4064)
			(end -0.7874 -0.4064)
			(stroke
				(width 0.1524)
				(type default)
			)
			(layer "F.SilkS")
		)
		(fp_line
			(start 0.7874 -0.4064)
			(end 0.7874 0.4064)
			(stroke
				(width 0.1524)
				(type default)
			)
			(layer "F.SilkS")
		)
		(fp_line
			(start 0.7874 0.4064)
			(end -0.7874 0.4064)
			(stroke
				(width 0.1524)
				(type default)
			)
			(layer "F.SilkS")
		)
		(fp_line
			(start -0.67945 -0.305054)
			(end -0.12065 -0.305054)
			(stroke
				(width 0.1)
				(type default)
			)
			(layer "F.Fab")
		)
		(fp_line
			(start -0.67945 0.3048)
			(end -0.67945 -0.305054)
			(stroke
				(width 0.1)
				(type default)
			)
			(layer "F.Fab")
		)
		(fp_line
			(start -0.12065 -0.305054)
			(end -0.12065 -0.2794)
			(stroke
				(width 0.1)
				(type default)
			)
			(layer "F.Fab")
		)
		(fp_line
			(start -0.12065 -0.2794)
			(end 0.12065 -0.2794)
			(stroke
				(width 0.1)
				(type default)
			)
			(layer "F.Fab")
		)
		(fp_line
			(start -0.12065 0.2794)
			(end -0.12065 0.3048)
			(stroke
				(width 0.1)
				(type default)
			)
			(layer "F.Fab")
		)
		(fp_line
			(start -0.12065 0.3048)
			(end -0.67945 0.3048)
			(stroke
				(width 0.1)
				(type default)
			)
			(layer "F.Fab")
		)
		(fp_line
			(start 0.120396 0.2794)
			(end -0.12065 0.2794)
			(stroke
				(width 0.1)
				(type default)
			)
			(layer "F.Fab")
		)
		(fp_line
			(start 0.120396 0.3048)
			(end 0.120396 0.2794)
			(stroke
				(width 0.1)
				(type default)
			)
			(layer "F.Fab")
		)
		(fp_line
			(start 0.12065 -0.3048)
			(end 0.67945 -0.3048)
			(stroke
				(width 0.1)
				(type default)
			)
			(layer "F.Fab")
		)
		(fp_line
			(start 0.12065 -0.2794)
			(end 0.12065 -0.3048)
			(stroke
				(width 0.1)
				(type default)
			)
			(layer "F.Fab")
		)
		(fp_line
			(start 0.67945 -0.3048)
			(end 0.67945 0.3048)
			(stroke
				(width 0.1)
				(type default)
			)
			(layer "F.Fab")
		)
		(fp_line
			(start 0.67945 0.3048)
			(end 0.120396 0.3048)
			(stroke
				(width 0.1)
				(type default)
			)
			(layer "F.Fab")
		)
		(pad "1" smd circle
			(at -0.40005 0)
			(size 0 0)
			(layers "F.Cu" "F.Mask" "F.Paste")
			(net "UART_PEX1_SDB_R_RX")
		)
		(pad "2" smd circle
			(at 0.40005 0)
			(size 0 0)
			(layers "F.Cu" "F.Mask" "F.Paste")
			(net "UART_PEX1_SDB_R1_RX")
		)
	)
	(footprint ""
		(layer "F.Cu")
		(at 458.394562 -309.334662 90)
		(property "Reference" "PR183"
			(at 0 0 90)
			(layer "F.SilkS")
			(hide yes)
			(effects
				(font
					(size 1.27 1.27)
				)
			)
		)
		(property "Value" ""
			(at 0 0 90)
			(layer "F.Fab")
			(effects
				(font
					(size 1.27 1.27)
				)
			)
		)
		(duplicate_pad_numbers_are_jumpers no)
		(fp_line
			(start 0.7874 -0.4064)
			(end 0.7874 0.4064)
			(stroke
				(width 0.1524)
				(type default)
			)
			(layer "F.SilkS")
		)
		(fp_line
			(start -0.7874 -0.4064)
			(end 0.7874 -0.4064)
			(stroke
				(width 0.1524)
				(type default)
			)
			(layer "F.SilkS")
		)
		(fp_line
			(start 0.7874 0.4064)
			(end -0.7874 0.4064)
			(stroke
				(width 0.1524)
				(type default)
			)
			(layer "F.SilkS")
		)
		(fp_line
			(start -0.7874 0.4064)
			(end -0.7874 -0.4064)
			(stroke
				(width 0.1524)
				(type default)
			)
			(layer "F.SilkS")
		)
		(fp_line
			(start -0.12065 -0.305054)
			(end -0.12065 -0.2794)
			(stroke
				(width 0.1)
				(type default)
			)
			(layer "F.Fab")
		)
		(fp_line
			(start -0.67945 -0.305054)
			(end -0.12065 -0.305054)
			(stroke
				(width 0.1)
				(type default)
			)
			(layer "F.Fab")
		)
		(fp_line
			(start 0.67945 -0.3048)
			(end 0.67945 0.3048)
			(stroke
				(width 0.1)
				(type default)
			)
			(layer "F.Fab")
		)
		(fp_line
			(start 0.12065 -0.3048)
			(end 0.67945 -0.3048)
			(stroke
				(width 0.1)
				(type default)
			)
			(layer "F.Fab")
		)
		(fp_line
			(start 0.12065 -0.2794)
			(end 0.12065 -0.3048)
			(stroke
				(width 0.1)
				(type default)
			)
			(layer "F.Fab")
		)
		(fp_line
			(start -0.12065 -0.2794)
			(end 0.12065 -0.2794)
			(stroke
				(width 0.1)
				(type default)
			)
			(layer "F.Fab")
		)
		(fp_line
			(start 0.120396 0.2794)
			(end -0.12065 0.2794)
			(stroke
				(width 0.1)
				(type default)
			)
			(layer "F.Fab")
		)
		(fp_line
			(start -0.12065 0.2794)
			(end -0.12065 0.3048)
			(stroke
				(width 0.1)
				(type default)
			)
			(layer "F.Fab")
		)
		(fp_line
			(start 0.67945 0.3048)
			(end 0.120396 0.3048)
			(stroke
				(width 0.1)
				(type default)
			)
			(layer "F.Fab")
		)
		(fp_line
			(start 0.120396 0.3048)
			(end 0.120396 0.2794)
			(stroke
				(width 0.1)
				(type default)
			)
			(layer "F.Fab")
		)
		(fp_line
			(start -0.12065 0.3048)
			(end -0.67945 0.3048)
			(stroke
				(width 0.1)
				(type default)
			)
			(layer "F.Fab")
		)
		(fp_line
			(start -0.67945 0.3048)
			(end -0.67945 -0.305054)
			(stroke
				(width 0.1)
				(type default)
			)
			(layer "F.Fab")
		)
		(pad "1" smd circle
			(at -0.40005 0 90)
			(size 0 0)
			(layers "F.Cu" "F.Mask" "F.Paste")
			(net "SH_P1V25_PEX3_FB_N")
		)
		(pad "2" smd circle
			(at 0.40005 0 90)
			(size 0 0)
			(layers "F.Cu" "F.Mask" "F.Paste")
			(net "P1V25_PEX3_FB")
		)
	)
	(footprint ""
		(layer "F.Cu")
		(at 4.140454 -369.232688 90)
		(property "Reference" "Q251"
			(at -1.7018 -2.250948 90)
			(unlocked yes)
			(layer "F.SilkS")
			(effects
				(font
					(size 0.7874 0.5842)
					(thickness 0.1524)
				)
				(justify left)
			)
		)
		(property "Value" ""
			(at 0 0 90)
			(layer "F.Fab")
			(effects
				(font
					(size 1.27 1.27)
				)
			)
		)
		(duplicate_pad_numbers_are_jumpers no)
		(fp_line
			(start 1.584198 -1.519936)
			(end 1.584198 1.519936)
			(stroke
				(width 0.1524)
				(type default)
			)
			(layer "F.SilkS")
		)
		(fp_line
			(start -1.584198 -1.519936)
			(end 1.584198 -1.519936)
			(stroke
				(width 0.1524)
				(type default)
			)
			(layer "F.SilkS")
		)
		(fp_line
			(start 1.584198 1.519936)
			(end -1.584198 1.519936)
			(stroke
				(width 0.1524)
				(type default)
			)
			(layer "F.SilkS")
		)
		(fp_line
			(start -1.584198 1.519936)
			(end -1.584198 -1.519936)
			(stroke
				(width 0.1524)
				(type default)
			)
			(layer "F.SilkS")
		)
		(fp_line
			(start 0.700024 -1.519936)
			(end 0.700024 1.519936)
			(stroke
				(width 0.1)
				(type default)
			)
			(layer "F.Fab")
		)
		(fp_line
			(start -0.700024 -1.519936)
			(end 0.700024 -1.519936)
			(stroke
				(width 0.1)
				(type default)
			)
			(layer "F.Fab")
		)
		(fp_line
			(start 0.700024 1.519936)
			(end -0.700024 1.519936)
			(stroke
				(width 0.1)
				(type default)
			)
			(layer "F.Fab")
		)
		(fp_line
			(start -0.700024 1.519936)
			(end -0.700024 -1.519936)
			(stroke
				(width 0.1)
				(type default)
			)
			(layer "F.Fab")
		)
		(pad "D" smd rect
			(at 0.999998 0)
			(size 0.8128 0.9144)
			(layers "F.Cu" "F.Mask" "F.Paste")
			(net "P3V3_USB_HUB")
		)
		(pad "G" smd rect
			(at -0.999998 -0.94996)
			(size 0.8128 0.9144)
			(layers "F.Cu" "F.Mask" "F.Paste")
			(net "PG12_USB_HUB_N")
		)
		(pad "S" smd rect
			(at -0.999998 0.94996)
			(size 0.8128 0.9144)
			(layers "F.Cu" "F.Mask" "F.Paste")
			(net "P3V3_AUX")
		)
	)
	(footprint ""
		(layer "F.Cu")
		(at 154.860244 -97.1804 180)
		(property "Reference" "R110"
			(at 0 0 180)
			(layer "F.SilkS")
			(hide yes)
			(effects
				(font
					(size 1.27 1.27)
				)
			)
		)
		(property "Value" ""
			(at 0 0 180)
			(layer "F.Fab")
			(effects
				(font
					(size 1.27 1.27)
				)
			)
		)
		(duplicate_pad_numbers_are_jumpers no)
		(fp_line
			(start 0.7874 0.4064)
			(end -0.7874 0.4064)
			(stroke
				(width 0.1524)
				(type default)
			)
			(layer "F.SilkS")
		)
		(fp_line
			(start 0.7874 -0.4064)
			(end 0.7874 0.4064)
			(stroke
				(width 0.1524)
				(type default)
			)
			(layer "F.SilkS")
		)
		(fp_line
			(start -0.7874 0.4064)
			(end -0.7874 -0.4064)
			(stroke
				(width 0.1524)
				(type default)
			)
			(layer "F.SilkS")
		)
		(fp_line
			(start -0.7874 -0.4064)
			(end 0.7874 -0.4064)
			(stroke
				(width 0.1524)
				(type default)
			)
			(layer "F.SilkS")
		)
		(fp_line
			(start 0.67945 0.3048)
			(end 0.120396 0.3048)
			(stroke
				(width 0.1)
				(type default)
			)
			(layer "F.Fab")
		)
		(fp_line
			(start 0.67945 -0.3048)
			(end 0.67945 0.3048)
			(stroke
				(width 0.1)
				(type default)
			)
			(layer "F.Fab")
		)
		(fp_line
			(start 0.12065 -0.2794)
			(end 0.12065 -0.3048)
			(stroke
				(width 0.1)
				(type default)
			)
			(layer "F.Fab")
		)
		(fp_line
			(start 0.12065 -0.3048)
			(end 0.67945 -0.3048)
			(stroke
				(width 0.1)
				(type default)
			)
			(layer "F.Fab")
		)
		(fp_line
			(start 0.120396 0.3048)
			(end 0.120396 0.2794)
			(stroke
				(width 0.1)
				(type default)
			)
			(layer "F.Fab")
		)
		(fp_line
			(start 0.120396 0.2794)
			(end -0.12065 0.2794)
			(stroke
				(width 0.1)
				(type default)
			)
			(layer "F.Fab")
		)
		(fp_line
			(start -0.12065 0.3048)
			(end -0.67945 0.3048)
			(stroke
				(width 0.1)
				(type default)
			)
			(layer "F.Fab")
		)
		(fp_line
			(start -0.12065 0.2794)
			(end -0.12065 0.3048)
			(stroke
				(width 0.1)
				(type default)
			)
			(layer "F.Fab")
		)
		(fp_line
			(start -0.12065 -0.2794)
			(end 0.12065 -0.2794)
			(stroke
				(width 0.1)
				(type default)
			)
			(layer "F.Fab")
		)
		(fp_line
			(start -0.12065 -0.305054)
			(end -0.12065 -0.2794)
			(stroke
				(width 0.1)
				(type default)
			)
			(layer "F.Fab")
		)
		(fp_line
			(start -0.67945 0.3048)
			(end -0.67945 -0.305054)
			(stroke
				(width 0.1)
				(type default)
			)
			(layer "F.Fab")
		)
		(fp_line
			(start -0.67945 -0.305054)
			(end -0.12065 -0.305054)
			(stroke
				(width 0.1)
				(type default)
			)
			(layer "F.Fab")
		)
		(pad "1" smd circle
			(at -0.40005 0 180)
			(size 0 0)
			(layers "F.Cu" "F.Mask" "F.Paste")
			(net "PRSNTB3_NIC2_N")
		)
		(pad "2" smd circle
			(at 0.40005 0 180)
			(size 0 0)
			(layers "F.Cu" "F.Mask" "F.Paste")
			(net "P3V3_AUX")
		)
	)
	(footprint ""
		(layer "F.Cu")
		(at 365.506 -201.803 180)
		(property "Reference" "R4698"
			(at 0 0 180)
			(layer "F.SilkS")
			(hide yes)
			(effects
				(font
					(size 1.27 1.27)
				)
			)
		)
		(property "Value" ""
			(at 0 0 180)
			(layer "F.Fab")
			(effects
				(font
					(size 1.27 1.27)
				)
			)
		)
		(duplicate_pad_numbers_are_jumpers no)
		(fp_line
			(start 0.7874 0.4064)
			(end -0.7874 0.4064)
			(stroke
				(width 0.1524)
				(type default)
			)
			(layer "F.SilkS")
		)
		(fp_line
			(start 0.7874 -0.4064)
			(end 0.7874 0.4064)
			(stroke
				(width 0.1524)
				(type default)
			)
			(layer "F.SilkS")
		)
		(fp_line
			(start -0.7874 0.4064)
			(end -0.7874 -0.4064)
			(stroke
				(width 0.1524)
				(type default)
			)
			(layer "F.SilkS")
		)
		(fp_line
			(start -0.7874 -0.4064)
			(end 0.7874 -0.4064)
			(stroke
				(width 0.1524)
				(type default)
			)
			(layer "F.SilkS")
		)
		(fp_line
			(start 0.67945 0.3048)
			(end 0.120396 0.3048)
			(stroke
				(width 0.1)
				(type default)
			)
			(layer "F.Fab")
		)
		(fp_line
			(start 0.67945 -0.3048)
			(end 0.67945 0.3048)
			(stroke
				(width 0.1)
				(type default)
			)
			(layer "F.Fab")
		)
		(fp_line
			(start 0.12065 -0.2794)
			(end 0.12065 -0.3048)
			(stroke
				(width 0.1)
				(type default)
			)
			(layer "F.Fab")
		)
		(fp_line
			(start 0.12065 -0.3048)
			(end 0.67945 -0.3048)
			(stroke
				(width 0.1)
				(type default)
			)
			(layer "F.Fab")
		)
		(fp_line
			(start 0.120396 0.3048)
			(end 0.120396 0.2794)
			(stroke
				(width 0.1)
				(type default)
			)
			(layer "F.Fab")
		)
		(fp_line
			(start 0.120396 0.2794)
			(end -0.12065 0.2794)
			(stroke
				(width 0.1)
				(type default)
			)
			(layer "F.Fab")
		)
		(fp_line
			(start -0.12065 0.3048)
			(end -0.67945 0.3048)
			(stroke
				(width 0.1)
				(type default)
			)
			(layer "F.Fab")
		)
		(fp_line
			(start -0.12065 0.2794)
			(end -0.12065 0.3048)
			(stroke
				(width 0.1)
				(type default)
			)
			(layer "F.Fab")
		)
		(fp_line
			(start -0.12065 -0.2794)
			(end 0.12065 -0.2794)
			(stroke
				(width 0.1)
				(type default)
			)
			(layer "F.Fab")
		)
		(fp_line
			(start -0.12065 -0.305054)
			(end -0.12065 -0.2794)
			(stroke
				(width 0.1)
				(type default)
			)
			(layer "F.Fab")
		)
		(fp_line
			(start -0.67945 0.3048)
			(end -0.67945 -0.305054)
			(stroke
				(width 0.1)
				(type default)
			)
			(layer "F.Fab")
		)
		(fp_line
			(start -0.67945 -0.305054)
			(end -0.12065 -0.305054)
			(stroke
				(width 0.1)
				(type default)
			)
			(layer "F.Fab")
		)
		(pad "1" smd circle
			(at -0.40005 0 180)
			(size 0 0)
			(layers "F.Cu" "F.Mask" "F.Paste")
			(net "GND")
		)
		(pad "2" smd circle
			(at 0.40005 0 180)
			(size 0 0)
			(layers "F.Cu" "F.Mask" "F.Paste")
			(net "PCA9555_0_PEX1_A2")
		)
	)
)
